(kicad_pcb
	(version 20260206)
	(generator "pcbnew")
	(generator_version "10.0")
	(general
		(thickness 1.6)
		(legacy_teardrops no)
	)
	(paper "A4")
	(title_block
		(title "01162023_DA0F0TEBIF0_F0T_Expander_BD_F_brd_V02_OCP.brd")
		(comment 1 "Grand Teton / footprints 958-960 of 9728")
	)
	(layers
		(0 "F.Cu" signal "TOP")
		(4 "In1.Cu" signal "GND")
		(6 "In2.Cu" signal "VCC")
		(8 "In3.Cu" signal "VCC1")
		(10 "In4.Cu" signal "GND1")
		(12 "In5.Cu" signal "IN1")
		(14 "In6.Cu" signal "GND2")
		(16 "In7.Cu" signal "IN2")
		(18 "In8.Cu" signal "GND3")
		(20 "In9.Cu" signal "IN3")
		(22 "In10.Cu" signal "GND4")
		(24 "In11.Cu" signal "IN4")
		(26 "In12.Cu" signal "GND5")
		(28 "In13.Cu" signal "IN5")
		(30 "In14.Cu" signal "GND6")
		(32 "In15.Cu" signal "IN6")
		(34 "In16.Cu" signal "GND7")
		(2 "B.Cu" signal "BOTTOM")
		(9 "F.Adhes" user "F.Adhesive")
		(11 "B.Adhes" user "B.Adhesive")
		(13 "F.Paste" user "Package Geometry/Pastemask Top")
		(15 "B.Paste" user "Package Geometry/Pastemask Bottom")
		(5 "F.SilkS" user "Ref Des/Silkscreen Top")
		(7 "B.SilkS" user "Ref Des/Silkscreen Bottom")
		(1 "F.Mask" user "Board Geometry/Soldermask Top")
		(3 "B.Mask" user "Board Geometry/Soldermask Bottom")
		(17 "Dwgs.User" user "User.Drawings")
		(19 "Cmts.User" user "User.Comments")
		(21 "Eco1.User" user "User.Eco1")
		(23 "Eco2.User" user "User.Eco2")
		(25 "Edge.Cuts" user "Board Geometry/Outline")
		(27 "Margin" user)
		(31 "F.CrtYd" user "Package Geometry/Place Bound Top")
		(29 "B.CrtYd" user "Package Geometry/Place Bound Bottom")
		(35 "F.Fab" user "Ref Des/Assembly Top")
		(33 "B.Fab" user "Ref Des/Assembly Bottom")
	)
	(footprint ""
		(layer "F.Cu")
		(at 103.376984 -392.15441 90)
		(property "Reference" "U353"
			(at -5.013198 -4.722114 90)
			(unlocked yes)
			(layer "F.SilkS")
			(effects
				(font
					(size 0.7874 0.5842)
					(thickness 0.1524)
				)
				(justify left)
			)
		)
		(property "Value" ""
			(at 0 0 90)
			(layer "F.Fab")
			(effects
				(font
					(size 1.27 1.27)
				)
			)
		)
		(duplicate_pad_numbers_are_jumpers no)
		(fp_line
			(start 0 -2.921)
			(end 0 -3.302)
			(stroke
				(width 0.1524)
				(type default)
			)
			(layer "F.SilkS")
		)
		(fp_line
			(start 2.500122 -2.500122)
			(end 2.500122 -1.778)
			(stroke
				(width 0.1524)
				(type default)
			)
			(layer "F.SilkS")
		)
		(fp_line
			(start 1.778 -2.500122)
			(end 2.500122 -2.500122)
			(stroke
				(width 0.1524)
				(type default)
			)
			(layer "F.SilkS")
		)
		(fp_line
			(start -2.500122 -2.500122)
			(end -1.778 -2.500122)
			(stroke
				(width 0.1524)
				(type default)
			)
			(layer "F.SilkS")
		)
		(fp_line
			(start -2.500122 -1.778)
			(end -2.500122 -2.500122)
			(stroke
				(width 0.1524)
				(type default)
			)
			(layer "F.SilkS")
		)
		(fp_line
			(start 2.921 -1.016)
			(end 3.683 -1.016)
			(stroke
				(width 0.1524)
				(type default)
			)
			(layer "F.SilkS")
		)
		(fp_line
			(start -2.921 0.508)
			(end -3.302 0.508)
			(stroke
				(width 0.1524)
				(type default)
			)
			(layer "F.SilkS")
		)
		(fp_line
			(start 2.921 1.524)
			(end 3.302 1.524)
			(stroke
				(width 0.1524)
				(type default)
			)
			(layer "F.SilkS")
		)
		(fp_line
			(start 2.500122 1.778)
			(end 2.500122 2.500122)
			(stroke
				(width 0.1524)
				(type default)
			)
			(layer "F.SilkS")
		)
		(fp_line
			(start 2.500122 2.500122)
			(end 1.778 2.500122)
			(stroke
				(width 0.1524)
				(type default)
			)
			(layer "F.SilkS")
		)
		(fp_line
			(start -1.778 2.500122)
			(end -2.500122 2.500122)
			(stroke
				(width 0.1524)
				(type default)
			)
			(layer "F.SilkS")
		)
		(fp_line
			(start -2.500122 2.500122)
			(end -2.500122 1.778)
			(stroke
				(width 0.1524)
				(type default)
			)
			(layer "F.SilkS")
		)
		(fp_line
			(start -0.508 2.921)
			(end -0.508 3.683)
			(stroke
				(width 0.1524)
				(type default)
			)
			(layer "F.SilkS")
		)
		(fp_poly
			(pts
				(xy -2.618994 -2.869946) (xy -3.052064 -2.003552) (xy -3.485388 -2.869946)
			)
			(stroke
				(width 0)
				(type default)
			)
			(fill yes)
			(layer "F.SilkS")
		)
		(fp_line
			(start 0 -2.921)
			(end 0 -3.302)
			(stroke
				(width 0.1)
				(type default)
			)
			(layer "F.Fab")
		)
		(fp_line
			(start 2.500122 -2.500122)
			(end 2.500122 2.500122)
			(stroke
				(width 0.1)
				(type default)
			)
			(layer "F.Fab")
		)
		(fp_line
			(start -2.500122 -2.500122)
			(end 2.500122 -2.500122)
			(stroke
				(width 0.1)
				(type default)
			)
			(layer "F.Fab")
		)
		(fp_line
			(start 2.921 -1.016)
			(end 3.683 -1.016)
			(stroke
				(width 0.1)
				(type default)
			)
			(layer "F.Fab")
		)
		(fp_line
			(start -2.921 0.508)
			(end -3.302 0.508)
			(stroke
				(width 0.1)
				(type default)
			)
			(layer "F.Fab")
		)
		(fp_line
			(start 2.921 1.524)
			(end 3.302 1.524)
			(stroke
				(width 0.1)
				(type default)
			)
			(layer "F.Fab")
		)
		(fp_line
			(start 2.500122 2.500122)
			(end -2.500122 2.500122)
			(stroke
				(width 0.1)
				(type default)
			)
			(layer "F.Fab")
		)
		(fp_line
			(start -2.500122 2.500122)
			(end -2.500122 -2.500122)
			(stroke
				(width 0.1)
				(type default)
			)
			(layer "F.Fab")
		)
		(fp_line
			(start -0.508 2.921)
			(end -0.508 3.683)
			(stroke
				(width 0.1)
				(type default)
			)
			(layer "F.Fab")
		)
		(fp_poly
			(pts
				(xy -3.7592 -1.933194) (xy -2.892806 -1.500124) (xy -3.7592 -1.0668)
			)
			(stroke
				(width 0)
				(type default)
			)
			(fill yes)
			(layer "F.Fab")
		)
		(fp_text user "28"
			(at -3.095752 -3.512312 90)
			(unlocked yes)
			(layer "F.SilkS")
			(effects
				(font
					(size 0.635 0.4064)
					(thickness 0.1524)
				)
			)
		)
		(fp_text user "22"
			(at 2.2352 -3.172968 90)
			(unlocked yes)
			(layer "F.SilkS")
			(effects
				(font
					(size 0.635 0.4064)
					(thickness 0.1524)
				)
			)
		)
		(fp_text user "21"
			(at 3.3909 -2.769362 0)
			(unlocked yes)
			(layer "F.SilkS")
			(effects
				(font
					(size 0.635 0.4064)
					(thickness 0.1524)
				)
			)
		)
		(fp_text user "15"
			(at 3.074416 2.158492 0)
			(unlocked yes)
			(layer "F.SilkS")
			(effects
				(font
					(size 0.635 0.4064)
					(thickness 0.1524)
				)
			)
		)
		(fp_text user "7"
			(at -3.162808 2.626868 0)
			(unlocked yes)
			(layer "F.SilkS")
			(effects
				(font
					(size 0.635 0.4064)
					(thickness 0.1524)
				)
			)
		)
		(fp_text user "8"
			(at -2.172462 3.042666 0)
			(unlocked yes)
			(layer "F.SilkS")
			(effects
				(font
					(size 0.635 0.4064)
					(thickness 0.1524)
				)
			)
		)
		(fp_text user "14"
			(at 2.581148 3.24993 0)
			(unlocked yes)
			(layer "F.SilkS")
			(effects
				(font
					(size 0.635 0.4064)
					(thickness 0.1524)
				)
			)
		)
		(fp_text user "22"
			(at 2.2352 -3.172968 90)
			(unlocked yes)
			(layer "F.Fab")
			(effects
				(font
					(size 0.635 0.4064)
					(thickness 0.1524)
				)
			)
		)
		(fp_text user "28"
			(at -2.2098 -3.172968 90)
			(unlocked yes)
			(layer "F.Fab")
			(effects
				(font
					(size 0.635 0.4064)
					(thickness 0.1524)
				)
			)
		)
		(fp_text user "21"
			(at 3.227832 -2.2606 180)
			(unlocked yes)
			(layer "F.Fab")
			(effects
				(font
					(size 0.635 0.4064)
					(thickness 0.1524)
				)
			)
		)
		(fp_text user "7"
			(at -3.147568 1.8034 180)
			(unlocked yes)
			(layer "F.Fab")
			(effects
				(font
					(size 0.635 0.4064)
					(thickness 0.1524)
				)
			)
		)
		(fp_text user "15"
			(at 3.253232 2.2352 180)
			(unlocked yes)
			(layer "F.Fab")
			(effects
				(font
					(size 0.635 0.4064)
					(thickness 0.1524)
				)
			)
		)
		(fp_text user "14"
			(at 2.1336 3.253232 90)
			(unlocked yes)
			(layer "F.Fab")
			(effects
				(font
					(size 0.635 0.4064)
					(thickness 0.1524)
				)
			)
		)
		(fp_text user "8"
			(at -1.8796 3.253232 90)
			(unlocked yes)
			(layer "F.Fab")
			(effects
				(font
					(size 0.635 0.4064)
					(thickness 0.1524)
				)
			)
		)
		(pad "1" smd rect
			(at -2.412492 -1.500124 180)
			(size 0.254 0.7366)
			(layers "F.Cu" "F.Mask" "F.Paste")
			(net "USB2_MB_BMC_R_DN")
		)
		(pad "2" smd rect
			(at -2.412492 -0.999998 180)
			(size 0.254 0.7366)
			(layers "F.Cu" "F.Mask" "F.Paste")
			(net "USB2_MB_BMC_R_DP")
		)
		(pad "3" smd rect
			(at -2.412492 -0.499872 180)
			(size 0.254 0.7366)
			(layers "F.Cu" "F.Mask" "F.Paste")
			(net "USB2_BIC_R_DN")
		)
		(pad "4" smd rect
			(at -2.412492 0 180)
			(size 0.254 0.7366)
			(layers "F.Cu" "F.Mask" "F.Paste")
			(net "USB2_BIC_R_DP")
		)
		(pad "5" smd rect
			(at -2.412492 0.499872 180)
			(size 0.254 0.7366)
			(layers "F.Cu" "F.Mask" "F.Paste")
			(net "P3V3_BIC_USB_HUB")
		)
		(pad "6" smd rect
			(at -2.412492 0.999998 180)
			(size 0.254 0.7366)
			(layers "F.Cu" "F.Mask" "F.Paste")
			(net "USB2_GPU_HMC_R_DN")
		)
		(pad "7" smd rect
			(at -2.412492 1.500124 180)
			(size 0.254 0.7366)
			(layers "F.Cu" "F.Mask" "F.Paste")
			(net "USB2_GPU_HMC_R_DP")
		)
		(pad "8" smd rect
			(at -1.500124 2.412492 90)
			(size 0.254 0.7366)
			(layers "F.Cu" "F.Mask" "F.Paste")
			(net "BIC_USB_HUB_RREF")
		)
		(pad "9" smd rect
			(at -0.999998 2.412492 90)
			(size 0.254 0.7366)
			(layers "F.Cu" "F.Mask" "F.Paste")
			(net "P3V3_BIC_USB_HUB")
		)
		(pad "10" smd rect
			(at -0.499872 2.412492 90)
			(size 0.254 0.7366)
			(layers "F.Cu" "F.Mask" "F.Paste")
			(net "BIC_USB_HUB_XIN")
		)
		(pad "11" smd rect
			(at 0 2.412492 90)
			(size 0.254 0.7366)
			(layers "F.Cu" "F.Mask" "F.Paste")
			(net "BIC_USB_HUB_XOUT")
		)
		(pad "12" smd rect
			(at 0.499872 2.412492 90)
			(size 0.254 0.7366)
			(layers "F.Cu" "F.Mask" "F.Paste")
			(net "Net_9079")
		)
		(pad "13" smd rect
			(at 0.999998 2.412492 90)
			(size 0.254 0.7366)
			(layers "F.Cu" "F.Mask" "F.Paste")
			(net "Net_9077")
		)
		(pad "14" smd rect
			(at 1.500124 2.412492 90)
			(size 0.254 0.7366)
			(layers "F.Cu" "F.Mask" "F.Paste")
			(net "P3V3_BIC_USB_HUB")
		)
		(pad "15" smd rect
			(at 2.412492 1.500124 180)
			(size 0.254 0.7366)
			(layers "F.Cu" "F.Mask" "F.Paste")
			(net "Net_9078")
		)
		(pad "16" smd rect
			(at 2.412492 0.999998 180)
			(size 0.254 0.7366)
			(layers "F.Cu" "F.Mask" "F.Paste")
			(net "Net_9076")
		)
		(pad "17" smd rect
			(at 2.412492 0.499872 180)
			(size 0.254 0.7366)
			(layers "F.Cu" "F.Mask" "F.Paste")
			(net "RST_BIC_USB_HUB_R1_N")
		)
		(pad "18" smd rect
			(at 2.412492 0 180)
			(size 0.254 0.7366)
			(layers "F.Cu" "F.Mask" "F.Paste")
			(net "BIC_USB_HUB_TEST")
		)
		(pad "19" smd rect
			(at 2.412492 -0.499872 180)
			(size 0.254 0.7366)
			(layers "F.Cu" "F.Mask" "F.Paste")
			(net "BIC_USB_HUB_OVCUR4")
		)
		(pad "20" smd rect
			(at 2.412492 -0.999998 180)
			(size 0.254 0.7366)
			(layers "F.Cu" "F.Mask" "F.Paste")
			(net "BIC_USB_HUB_OVCUR3")
		)
		(pad "21" smd rect
			(at 2.412492 -1.500124 180)
			(size 0.254 0.7366)
			(layers "F.Cu" "F.Mask" "F.Paste")
			(net "P3V3_BIC_USB_HUB")
		)
		(pad "22" smd rect
			(at 1.500124 -2.412492 90)
			(size 0.254 0.7366)
			(layers "F.Cu" "F.Mask" "F.Paste")
			(net "BIC_USB_HUB_PSELF")
		)
		(pad "23" smd rect
			(at 0.999998 -2.412492 90)
			(size 0.254 0.7366)
			(layers "F.Cu" "F.Mask" "F.Paste")
			(net "BIC_USB_HUB_PGANG")
		)
		(pad "24" smd rect
			(at 0.499872 -2.412492 90)
			(size 0.254 0.7366)
			(layers "F.Cu" "F.Mask" "F.Paste")
			(net "BIC_USB_HUB_OVCUR2")
		)
		(pad "25" smd rect
			(at 0 -2.412492 90)
			(size 0.254 0.7366)
			(layers "F.Cu" "F.Mask" "F.Paste")
			(net "BIC_USB_HUB_OVCUR1")
		)
		(pad "26" smd rect
			(at -0.499872 -2.412492 90)
			(size 0.254 0.7366)
			(layers "F.Cu" "F.Mask" "F.Paste")
			(net "Net_9075")
		)
		(pad "27" smd rect
			(at -0.999998 -2.412492 90)
			(size 0.254 0.7366)
			(layers "F.Cu" "F.Mask" "F.Paste")
			(net "P3V3_BIC_USB_HUB")
		)
		(pad "28" smd rect
			(at -1.500124 -2.412492 90)
			(size 0.254 0.7366)
			(layers "F.Cu" "F.Mask" "F.Paste")
			(net "P3V3_BIC_USB_HUB")
		)
		(pad "TH" smd rect
			(at 0 0 90)
			(size 3.556 3.556)
			(layers "F.Cu" "F.Mask" "F.Paste")
			(net "GND")
		)
		(zone
			(layer "F.Cu")
			(hatch none 0.5)
			(connect_pads
				(clearance 0)
			)
			(min_thickness 0.25)
			(keepout
				(tracks not_allowed)
				(vias allowed)
				(pads allowed)
				(copperpour not_allowed)
				(footprints allowed)
			)
			(placement
				(enabled no)
				(sheetname "")
			)
			(fill
				(thermal_gap 0.5)
				(thermal_bridge_width 0.5)
				(island_removal_mode 0)
			)
			(polygon
				(pts
					(xy 101.395784 -393.09421) (xy 101.548184 -393.09421) (xy 101.548184 -390.32561) (xy 105.205784 -390.32561)
					(xy 105.205784 -393.98321) (xy 101.548184 -393.98321) (xy 101.548184 -393.11961) (xy 101.395784 -393.11961)
					(xy 101.395784 -394.13561) (xy 105.358184 -394.13561) (xy 105.358184 -390.17321) (xy 101.395784 -390.17321)
				)
			)
		)
	)
	(footprint ""
		(layer "F.Cu")
		(at 370.571776 -152.71115 90)
		(property "Reference" "R747"
			(at 0 0 90)
			(layer "F.SilkS")
			(hide yes)
			(effects
				(font
					(size 1.27 1.27)
				)
			)
		)
		(property "Value" ""
			(at 0 0 90)
			(layer "F.Fab")
			(effects
				(font
					(size 1.27 1.27)
				)
			)
		)
		(duplicate_pad_numbers_are_jumpers no)
		(fp_line
			(start 0.7874 -0.4064)
			(end 0.7874 0.4064)
			(stroke
				(width 0.1524)
				(type default)
			)
			(layer "F.SilkS")
		)
		(fp_line
			(start -0.7874 -0.4064)
			(end 0.7874 -0.4064)
			(stroke
				(width 0.1524)
				(type default)
			)
			(layer "F.SilkS")
		)
		(fp_line
			(start 0.7874 0.4064)
			(end -0.7874 0.4064)
			(stroke
				(width 0.1524)
				(type default)
			)
			(layer "F.SilkS")
		)
		(fp_line
			(start -0.7874 0.4064)
			(end -0.7874 -0.4064)
			(stroke
				(width 0.1524)
				(type default)
			)
			(layer "F.SilkS")
		)
		(fp_line
			(start -0.12065 -0.305054)
			(end -0.12065 -0.2794)
			(stroke
				(width 0.1)
				(type default)
			)
			(layer "F.Fab")
		)
		(fp_line
			(start -0.67945 -0.305054)
			(end -0.12065 -0.305054)
			(stroke
				(width 0.1)
				(type default)
			)
			(layer "F.Fab")
		)
		(fp_line
			(start 0.67945 -0.3048)
			(end 0.67945 0.3048)
			(stroke
				(width 0.1)
				(type default)
			)
			(layer "F.Fab")
		)
		(fp_line
			(start 0.12065 -0.3048)
			(end 0.67945 -0.3048)
			(stroke
				(width 0.1)
				(type default)
			)
			(layer "F.Fab")
		)
		(fp_line
			(start 0.12065 -0.2794)
			(end 0.12065 -0.3048)
			(stroke
				(width 0.1)
				(type default)
			)
			(layer "F.Fab")
		)
		(fp_line
			(start -0.12065 -0.2794)
			(end 0.12065 -0.2794)
			(stroke
				(width 0.1)
				(type default)
			)
			(layer "F.Fab")
		)
		(fp_line
			(start 0.120396 0.2794)
			(end -0.12065 0.2794)
			(stroke
				(width 0.1)
				(type default)
			)
			(layer "F.Fab")
		)
		(fp_line
			(start -0.12065 0.2794)
			(end -0.12065 0.3048)
			(stroke
				(width 0.1)
				(type default)
			)
			(layer "F.Fab")
		)
		(fp_line
			(start 0.67945 0.3048)
			(end 0.120396 0.3048)
			(stroke
				(width 0.1)
				(type default)
			)
			(layer "F.Fab")
		)
		(fp_line
			(start 0.120396 0.3048)
			(end 0.120396 0.2794)
			(stroke
				(width 0.1)
				(type default)
			)
			(layer "F.Fab")
		)
		(fp_line
			(start -0.12065 0.3048)
			(end -0.67945 0.3048)
			(stroke
				(width 0.1)
				(type default)
			)
			(layer "F.Fab")
		)
		(fp_line
			(start -0.67945 0.3048)
			(end -0.67945 -0.305054)
			(stroke
				(width 0.1)
				(type default)
			)
			(layer "F.Fab")
		)
		(pad "1" smd circle
			(at -0.40005 0 90)
			(size 0 0)
			(layers "F.Cu" "F.Mask" "F.Paste")
			(net "NIC6_ADC_A1")
		)
		(pad "2" smd circle
			(at 0.40005 0 90)
			(size 0 0)
			(layers "F.Cu" "F.Mask" "F.Paste")
			(net "P3V3_AUX")
		)
	)
	(footprint ""
		(layer "F.Cu")
		(at 338.074 -164.973 180)
		(property "Reference" "R4774"
			(at 0 0 180)
			(layer "F.SilkS")
			(hide yes)
			(effects
				(font
					(size 1.27 1.27)
				)
			)
		)
		(property "Value" ""
			(at 0 0 180)
			(layer "F.Fab")
			(effects
				(font
					(size 1.27 1.27)
				)
			)
		)
		(duplicate_pad_numbers_are_jumpers no)
		(fp_line
			(start 0.7874 0.4064)
			(end -0.7874 0.4064)
			(stroke
				(width 0.1524)
				(type default)
			)
			(layer "F.SilkS")
		)
		(fp_line
			(start 0.7874 -0.4064)
			(end 0.7874 0.4064)
			(stroke
				(width 0.1524)
				(type default)
			)
			(layer "F.SilkS")
		)
		(fp_line
			(start -0.7874 0.4064)
			(end -0.7874 -0.4064)
			(stroke
				(width 0.1524)
				(type default)
			)
			(layer "F.SilkS")
		)
		(fp_line
			(start -0.7874 -0.4064)
			(end 0.7874 -0.4064)
			(stroke
				(width 0.1524)
				(type default)
			)
			(layer "F.SilkS")
		)
		(fp_line
			(start 0.67945 0.3048)
			(end 0.120396 0.3048)
			(stroke
				(width 0.1)
				(type default)
			)
			(layer "F.Fab")
		)
		(fp_line
			(start 0.67945 -0.3048)
			(end 0.67945 0.3048)
			(stroke
				(width 0.1)
				(type default)
			)
			(layer "F.Fab")
		)
		(fp_line
			(start 0.12065 -0.2794)
			(end 0.12065 -0.3048)
			(stroke
				(width 0.1)
				(type default)
			)
			(layer "F.Fab")
		)
		(fp_line
			(start 0.12065 -0.3048)
			(end 0.67945 -0.3048)
			(stroke
				(width 0.1)
				(type default)
			)
			(layer "F.Fab")
		)
		(fp_line
			(start 0.120396 0.3048)
			(end 0.120396 0.2794)
			(stroke
				(width 0.1)
				(type default)
			)
			(layer "F.Fab")
		)
		(fp_line
			(start 0.120396 0.2794)
			(end -0.12065 0.2794)
			(stroke
				(width 0.1)
				(type default)
			)
			(layer "F.Fab")
		)
		(fp_line
			(start -0.12065 0.3048)
			(end -0.67945 0.3048)
			(stroke
				(width 0.1)
				(type default)
			)
			(layer "F.Fab")
		)
		(fp_line
			(start -0.12065 0.2794)
			(end -0.12065 0.3048)
			(stroke
				(width 0.1)
				(type default)
			)
			(layer "F.Fab")
		)
		(fp_line
			(start -0.12065 -0.2794)
			(end 0.12065 -0.2794)
			(stroke
				(width 0.1)
				(type default)
			)
			(layer "F.Fab")
		)
		(fp_line
			(start -0.12065 -0.305054)
			(end -0.12065 -0.2794)
			(stroke
				(width 0.1)
				(type default)
			)
			(layer "F.Fab")
		)
		(fp_line
			(start -0.67945 0.3048)
			(end -0.67945 -0.305054)
			(stroke
				(width 0.1)
				(type default)
			)
			(layer "F.Fab")
		)
		(fp_line
			(start -0.67945 -0.305054)
			(end -0.12065 -0.305054)
			(stroke
				(width 0.1)
				(type default)
			)
			(layer "F.Fab")
		)
		(pad "1" smd circle
			(at -0.40005 0 180)
			(size 0 0)
			(layers "F.Cu" "F.Mask" "F.Paste")
			(net "RST_PEX_SSD11_PERST_N")
		)
		(pad "2" smd circle
			(at 0.40005 0 180)
			(size 0 0)
			(layers "F.Cu" "F.Mask" "F.Paste")
			(net "RST_PEX_SSD11_PERST_R_N")
		)
	)
)
